FILE_TYPE = CONNECTIVITY;
{Allegro Design Entry HDL 17.2-2016 S066 (3851973) 4/6/2020}
"PAGE_NUMBER" = 7;
0"NC";
1"SG\g";
2"XP3R3V_FPGA\g";
3"XP3R3V_FPGA\g";
4"SG\g";
5"XP3R3V_FPGA\g";
6"SG\g";
7"SG\g";
8"XP3R3V_FPGA\g";
9"XP3R3V_FPGA\g";
10"R_SHT3X_ALERT_N";
11"FPGA_IN_SHT3X_ALERT_N";
12"R_SHT3X_RST_N";
13"R_SHT3X_I2C_SCL";
14"R_SHT3X_I2C_SDA";
15"VDD3V3_SHT31A";
16"FPGA_OUT_SHT3X_RST_N";
17"SHT3X_ADDR";
18"SHT3X_I2C_SDA";
19"SHT3X_I2C_SCL";
%"RESISTOR"
"1","(-9300,8950)","0","passive","I13";
;
$LOCATION"R67"
CDS_LOCATION"R67"
$SEC"1"
CDS_SEC"1"
VALUE"33OHM"
PACKAGE"0402"
TOLERANCE"1%"
CLS_PN"G155-133R0-01"
CDS_LIB"passive"
CDS_LMAN_SYM_OUTLINE"-50,50,100,-50"
SIGNAL_MODEL"DEFAULT_RESISTOR_33OHM_2_1";
"1"
$PN"1"19;
"2"
$PN"2"13;
%"RESISTOR"
"1","(-9300,9050)","0","passive","I14";
;
$LOCATION"R66"
CDS_LOCATION"R66"
$SEC"1"
CDS_SEC"1"
VALUE"33OHM"
PACKAGE"0402"
TOLERANCE"1%"
CLS_PN"G155-133R0-01"
SIGNAL_MODEL"DEFAULT_RESISTOR_33OHM_2_1"
CDS_LMAN_SYM_OUTLINE"-50,50,100,-50"
CDS_LIB"passive";
"1"
$PN"1"18;
"2"
$PN"2"14;
%"VCC"
"1","(-10450,10000)","0","cls","I15";
;
HDL_POWER"XP3R3V_FPGA"
VOLTAGE"3.3V"
BODY_TYPE"PLUMBING"
CDS_LMAN_SYM_OUTLINE"-250,250,250,-250"
CDS_LIB"cls";
"$PIN0"9;
%"VCC"
"1","(-9150,8450)","0","cls","I17";
;
HDL_POWER"XP3R3V_FPGA"
VOLTAGE"3.3V"
BODY_TYPE"PLUMBING"
CDS_LIB"cls"
CDS_LMAN_SYM_OUTLINE"-250,250,250,-250";
"$PIN0"5;
%"CAPACITOR"
"2","(-4300,8750)","2","passive","I18";
;
$LOCATION"C40"
CDS_LOCATION"C40"
$SEC"1"
CDS_SEC"1"
PACKAGE"0402"
VOLTAGE"25V"
VALUE"0.1UF"
CLS_PN"G105-0B104-EK"
CDS_LMAN_SYM_OUTLINE"-50,0,50,-50"
CDS_LIB"passive"
TOLERANCE"10%";
"2"
$PN"2"7;
"1"
$PN"1"8;
%"CAPACITOR"
"2","(-5650,8750)","2","passive","I19";
;
$LOCATION"C275"
CDS_LOCATION"C275"
$SEC"1"
CDS_SEC"1"
PACKAGE"0402"
VOLTAGE"25V"
VALUE"0.1UF"
CLS_PN"G105-0B104-EK"
CDS_LMAN_SYM_OUTLINE"-50,0,50,-50"
CDS_LIB"passive"
TOLERANCE"10%";
"2"
$PN"2"7;
"1"
$PN"1"15;
%"VCC"
"1","(-4050,9250)","0","cls","I20";
;
HDL_POWER"XP3R3V_FPGA"
VOLTAGE"3.3V"
CDS_LIB"cls"
CDS_LMAN_SYM_OUTLINE"-250,250,250,-250"
BODY_TYPE"PLUMBING";
"$PIN0"8;
%"FERRITEBEAD"
"1","(-4650,9100)","2","passive","I21";
;
$LOCATION"L17"
CDS_LOCATION"L17"
$SEC"1"
CDS_SEC"1"
VALUE"600OHM"
PACKAGE"0603"
DCR"1300MA 0.15OHM"
CDS_LIB"passive"
CDS_LMAN_SYM_OUTLINE"0,0,200,-100"
CLS_PN"G191-10097-01"
TOLERANCE"25%";
"2"
$PN"2"15;
"1"
$PN"1"8;
%"GND_SG"
"1","(-5600,8200)","2","cls","I22";
;
HDL_POWER"SG"
CDS_LMAN_SYM_OUTLINE"0,0,100,-50"
CDS_LIB"cls"
BODY_TYPE"PLUMBING";
"SGND"7;
%"CAPACITOR"
"2","(-5200,8750)","2","passive","I23";
;
$LOCATION"C274"
CDS_LOCATION"C274"
$SEC"1"
CDS_SEC"1"
VALUE"10UF"
PACKAGE"0402"
VOLTAGE"6.3V"
CDS_LIB"passive"
CDS_LMAN_SYM_OUTLINE"-50,0,50,-50"
CLS_PN"G105-0C106-BM"
TOLERANCE"20%";
"2"
$PN"2"7;
"1"
$PN"1"15;
%"GND_SG"
"1","(-7950,8050)","0","cls","I25";
;
HDL_POWER"SG"
BODY_TYPE"PLUMBING"
CDS_LMAN_SYM_OUTLINE"0,0,100,-50"
CDS_LIB"cls";
"SGND"6;
%"RESISTOR"
"2","(-10400,9550)","0","passive","I3";
;
$LOCATION"R64"
CDS_LOCATION"R64"
$SEC"1"
CDS_SEC"1"
PACKAGE"0402"
VALUE"4.7KOHM"
TOLERANCE"1%"
CLS_PN"G155-14701-01"
CDS_LMAN_SYM_OUTLINE"-50,50,50,-100"
CDS_LIB"passive";
"1"
$PN"1"9;
"2"
$PN"2"18;
%"RESISTOR"
"1","(-4550,7050)","0","passive","I33";
;
$LOCATION"R298"
CDS_LOCATION"R298"
$SEC"1"
CDS_SEC"1"
VALUE"33OHM"
PACKAGE"0402"
TOLERANCE"1%"
CLS_PN"G155-133R0-01"
CDS_LIB"passive"
CDS_LMAN_SYM_OUTLINE"-50,50,100,-50"
SIGNAL_MODEL"DEFAULT_RESISTOR_33OHM_2_1";
"1"
$PN"1"12;
"2"
$PN"2"16;
%"GND_SG"
"1","(-5100,6200)","0","cls","I36";
;
HDL_POWER"SG"
BODY_TYPE"PLUMBING"
CDS_LIB"cls"
CDS_LMAN_SYM_OUTLINE"0,0,100,-50";
"SGND"4;
%"VCC"
"1","(-5150,7800)","0","cls","I37";
;
HDL_POWER"XP3R3V_FPGA"
VOLTAGE"3.3V"
BODY_TYPE"PLUMBING"
CDS_LMAN_SYM_OUTLINE"-250,250,250,-250"
CDS_LIB"cls";
"$PIN0"3;
%"RESISTOR"
"2","(-5100,7500)","0","passive","I38";
;
LOCATION"R296"
$SEC"1"
CDS_SEC"1"
VALUE"4.7KOHM"
PACKAGE"0402"
TOLERANCE"1%"
CLS_PN"G155-14701-01"
CDS_LMAN_SYM_OUTLINE"-50,50,50,-100"
CDS_LIB"passive";
"1"
$PN"1"3;
"2"
$PN"2"12;
%"RESISTOR"
"2","(-5050,6600)","0","passive","I39";
;
LOCATION"R297"
$SEC"1"
CDS_SEC"1"
PACKAGE"0402"
NO_ASSY"TRUE"
VALUE"4.7KOHM"
TOLERANCE"1%"
CDS_LIB"passive"
CDS_LMAN_SYM_OUTLINE"-50,50,50,-100"
CLS_PN"G155-14701-01";
"1"
$PN"1"12;
"2"
$PN"2"4;
%"RESISTOR"
"2","(-9950,9550)","0","passive","I4";
;
$LOCATION"R65"
CDS_LOCATION"R65"
$SEC"1"
CDS_SEC"1"
VALUE"4.7KOHM"
PACKAGE"0402"
TOLERANCE"1%"
CLS_PN"G155-14701-01"
CDS_LMAN_SYM_OUTLINE"-50,50,50,-100"
CDS_LIB"passive";
"1"
$PN"1"9;
"2"
$PN"2"19;
%"RESISTOR"
"1","(-4550,6950)","0","passive","I40";
;
$LOCATION"R299"
CDS_LOCATION"R299"
$SEC"1"
CDS_SEC"1"
VALUE"33OHM"
PACKAGE"0402"
TOLERANCE"1%"
CLS_PN"G155-133R0-01"
SIGNAL_MODEL"DEFAULT_RESISTOR_33OHM_2_1"
CDS_LMAN_SYM_OUTLINE"-50,50,100,-50"
CDS_LIB"passive";
"1"
$PN"1"10;
"2"
$PN"2"11;
%"RESISTOR"
"2","(-3800,7500)","0","passive","I41";
;
$LOCATION"R300"
CDS_LOCATION"R300"
$SEC"1"
CDS_SEC"1"
PACKAGE"0402"
VALUE"4.7KOHM"
TOLERANCE"1%"
CDS_LIB"passive"
CDS_LMAN_SYM_OUTLINE"-50,50,50,-100"
CLS_PN"G155-14701-01";
"1"
$PN"1"2;
"2"
$PN"2"11;
%"VCC"
"1","(-3850,7800)","0","cls","I42";
;
HDL_POWER"XP3R3V_FPGA"
VOLTAGE"3.3V"
BODY_TYPE"PLUMBING"
CDS_LMAN_SYM_OUTLINE"-250,250,250,-250"
CDS_LIB"cls";
"$PIN0"2;
%"SHT31A_DIS_B10KS_DFN8"
"1","(-6650,9150)","2","analog","I44";
;
$LOCATION"U27"
CDS_LOCATION"U27"
$SEC"1"
CDS_SEC"1"
CLS_PN"A222-00001-FB"
VALUE"SHT31A-DIS-B10KS"
CDS_LMAN_SYM_OUTLINE"0,0,1000,-1000"
CDS_LIB"analog";
"THRM_PAD"
$PN"9"6;
"VSS"
$PN"8"6;
"R"
$PN"7"6;
"RESET* \B"
$PN"6"12;
"VDD"
$PN"5"15;
"SCL"
$PN"4"13;
"ALERT"
$PN"3"10;
"ADDR"
$PN"2"17;
"SDA"
$PN"1"14;
%"GND_SG"
"1","(-9150,7300)","0","cls","I6";
;
HDL_POWER"SG"
BODY_TYPE"PLUMBING"
CDS_LIB"cls"
CDS_LMAN_SYM_OUTLINE"0,0,100,-50";
"SGND"1;
%"RESISTOR"
"2","(-9100,7600)","0","passive","I7";
;
$LOCATION"R69"
CDS_LOCATION"R69"
$SEC"1"
CDS_SEC"1"
VALUE"1KOHM"
PACKAGE"0402"
TOLERANCE"1%"
CDS_LIB"passive"
CDS_LMAN_SYM_OUTLINE"-50,50,50,-100"
CLS_PN"G155-11001-01";
"1"
$PN"1"17;
"2"
$PN"2"1;
%"RESISTOR"
"2","(-9100,8200)","0","passive","I8";
;
$LOCATION"R68"
CDS_LOCATION"R68"
$SEC"1"
CDS_SEC"1"
NO_ASSY"TRUE"
VALUE"4.7KOHM"
PACKAGE"0402"
TOLERANCE"1%"
CDS_LIB"passive"
CDS_LMAN_SYM_OUTLINE"-50,50,50,-100"
CLS_PN"G155-14701-01";
"1"
$PN"1"5;
"2"
$PN"2"17;
END.
